(kicad_pcb
	(version 20260206)
	(generator "pcbnew")
	(generator_version "10.0")
	(general
		(thickness 1.6)
		(legacy_teardrops no)
	)
	(paper "A4")
	(title_block
		(title "Bryce Canyon_F.DPB_16315-1-OCP.brd")
		(comment 1 "Bryce Canyon / footprints 1448-1455 of 2223")
	)
	(layers
		(0 "F.Cu" signal "TOP")
		(4 "In1.Cu" signal "L2GND")
		(6 "In2.Cu" signal "L3")
		(8 "In3.Cu" signal "L4GND")
		(10 "In4.Cu" signal "L5")
		(12 "In5.Cu" signal "L6VCC")
		(14 "In6.Cu" signal "L7VCC")
		(16 "In7.Cu" signal "L8")
		(18 "In8.Cu" signal "L9GND")
		(20 "In9.Cu" signal "L10")
		(22 "In10.Cu" signal "L11GND")
		(2 "B.Cu" signal "BOTTOM")
		(9 "F.Adhes" user "F.Adhesive")
		(11 "B.Adhes" user "B.Adhesive")
		(13 "F.Paste" user "Package Geometry/Pastemask Top")
		(15 "B.Paste" user "Package Geometry/Pastemask Bottom")
		(5 "F.SilkS" user "Ref Des/Silkscreen Top")
		(7 "B.SilkS" user "Ref Des/Silkscreen Bottom")
		(1 "F.Mask" user "Board Geometry/Soldermask Top")
		(3 "B.Mask" user "Board Geometry/Soldermask Bottom")
		(17 "Dwgs.User" user "User.Drawings")
		(19 "Cmts.User" user "User.Comments")
		(21 "Eco1.User" user "User.Eco1")
		(23 "Eco2.User" user "User.Eco2")
		(25 "Edge.Cuts" user "Board Geometry/Outline")
		(27 "Margin" user)
		(31 "F.CrtYd" user "Package Geometry/Place Bound Top")
		(29 "B.CrtYd" user "Package Geometry/Place Bound Bottom")
		(35 "F.Fab" user "Ref Des/Assembly Top")
		(33 "B.Fab" user "Ref Des/Assembly Bottom")
	)
	(footprint ""
		(layer "F.Cu")
		(at 370.8908 -132.1054)
		(property "Reference" "C564"
			(at 0 0 0)
			(layer "F.SilkS")
			(hide yes)
			(effects
				(font
					(size 1.27 1.27)
				)
			)
		)
		(property "Value" "SCD1U25V2KX-2-GP"
			(at 1.1811 -2.7051 0)
			(unlocked yes)
			(layer "F.Fab")
			(hide yes)
			(effects
				(font
					(size 1.016 1.016)
					(thickness 0.1524)
				)
			)
		)
		(property "Device Type" "C402H22"
			(at 1.1811 -4.2291 0)
			(unlocked yes)
			(layer "F.Fab")
			(hide yes)
			(effects
				(font
					(size 1.016 1.016)
					(thickness 0.1524)
				)
			)
		)
		(duplicate_pad_numbers_are_jumpers no)
		(fp_rect
			(start -0.4318 0.9525)
			(end 0.4318 -0.9525)
			(stroke
				(width 0)
				(type default)
			)
			(fill no)
			(layer "F.CrtYd")
		)
		(fp_rect
			(start -0.4318 0.9525)
			(end 0.4318 -0.9525)
			(stroke
				(width 0)
				(type default)
			)
			(fill no)
			(layer "F.Fab")
		)
		(pad "1" smd custom
			(at 0 -0.4445)
			(size 0.1524 0.1524)
			(layers "F.Cu" "F.Mask" "F.Paste")
			(net "MB1_ISTART_R")
			(options
				(clearance outline)
				(anchor circle)
			)
			(primitives
				(gr_poly
					(pts
						(arc
							(start 0.3048 -0.2032)
							(mid 0.275042 -0.275042)
							(end 0.2032 -0.3048)
						)
						(arc
							(start -0.2032 -0.3048)
							(mid -0.275042 -0.275042)
							(end -0.3048 -0.2032)
						)
						(arc
							(start -0.3048 0.2032)
							(mid -0.275042 0.275042)
							(end -0.2032 0.3048)
						)
						(arc
							(start 0.2032 0.3048)
							(mid 0.275042 0.275042)
							(end 0.3048 0.2032)
						)
					)
					(width 0)
					(fill yes)
				)
			)
		)
		(pad "2" smd custom
			(at 0 0.4445)
			(size 0.1524 0.1524)
			(layers "F.Cu" "F.Mask" "F.Paste")
			(net "AGND_CURRENT_MONOB")
			(options
				(clearance outline)
				(anchor circle)
			)
			(primitives
				(gr_poly
					(pts
						(arc
							(start 0.3048 -0.2032)
							(mid 0.275042 -0.275042)
							(end 0.2032 -0.3048)
						)
						(arc
							(start -0.2032 -0.3048)
							(mid -0.275042 -0.275042)
							(end -0.3048 -0.2032)
						)
						(arc
							(start -0.3048 0.2032)
							(mid -0.275042 0.275042)
							(end -0.2032 0.3048)
						)
						(arc
							(start 0.2032 0.3048)
							(mid 0.275042 0.275042)
							(end 0.3048 0.2032)
						)
					)
					(width 0)
					(fill yes)
				)
			)
		)
	)
	(footprint ""
		(layer "F.Cu")
		(at 190.246 -169.926)
		(property "Reference" "R525"
			(at 0 0 0)
			(layer "F.SilkS")
			(hide yes)
			(effects
				(font
					(size 1.27 1.27)
				)
			)
		)
		(property "Value" "220R3F-1-GP"
			(at -0.0254 -2.5146 0)
			(unlocked yes)
			(layer "F.Fab")
			(hide yes)
			(effects
				(font
					(size 1.016 1.016)
					(thickness 0.1524)
				)
			)
		)
		(property "Device Type" "R603H22"
			(at -0.0254 -4.0386 0)
			(unlocked yes)
			(layer "F.Fab")
			(hide yes)
			(effects
				(font
					(size 1.016 1.016)
					(thickness 0.1524)
				)
			)
		)
		(duplicate_pad_numbers_are_jumpers no)
		(fp_line
			(start -0.4826 0)
			(end -0.2032 0)
			(stroke
				(width 0.2032)
				(type default)
			)
			(layer "F.SilkS")
		)
		(fp_line
			(start 0.2032 0)
			(end 0.4826 0)
			(stroke
				(width 0.2032)
				(type default)
			)
			(layer "F.SilkS")
		)
		(fp_rect
			(start -0.5842 1.3335)
			(end 0.5842 -1.3335)
			(stroke
				(width 0)
				(type default)
			)
			(fill no)
			(layer "F.CrtYd")
		)
		(fp_rect
			(start -0.5842 1.3335)
			(end 0.5842 -1.3335)
			(stroke
				(width 0)
				(type default)
			)
			(fill no)
			(layer "F.Fab")
		)
		(pad "1" smd custom
			(at 0 -0.762)
			(size 0.2159 0.2159)
			(layers "F.Cu" "F.Mask" "F.Paste")
			(net "HDD_PRSNT_17")
			(options
				(clearance outline)
				(anchor circle)
			)
			(primitives
				(gr_poly
					(pts
						(arc
							(start -0.3302 -0.4318)
							(mid -0.402042 -0.402042)
							(end -0.4318 -0.3302)
						)
						(arc
							(start -0.4318 0.3302)
							(mid -0.402042 0.402042)
							(end -0.3302 0.4318)
						)
						(arc
							(start 0.3302 0.4318)
							(mid 0.402042 0.402042)
							(end 0.4318 0.3302)
						)
						(arc
							(start 0.4318 -0.3302)
							(mid 0.402042 -0.402042)
							(end 0.3302 -0.4318)
						)
					)
					(width 0)
					(fill yes)
				)
			)
		)
		(pad "2" smd custom
			(at 0 0.762)
			(size 0.2159 0.2159)
			(layers "F.Cu" "F.Mask" "F.Paste")
			(net "DRIVE_A_17_INS")
			(options
				(clearance outline)
				(anchor circle)
			)
			(primitives
				(gr_poly
					(pts
						(arc
							(start -0.3302 -0.4318)
							(mid -0.402042 -0.402042)
							(end -0.4318 -0.3302)
						)
						(arc
							(start -0.4318 0.3302)
							(mid -0.402042 0.402042)
							(end -0.3302 0.4318)
						)
						(arc
							(start 0.3302 0.4318)
							(mid 0.402042 0.402042)
							(end 0.4318 0.3302)
						)
						(arc
							(start 0.4318 -0.3302)
							(mid 0.402042 -0.402042)
							(end 0.3302 -0.4318)
						)
					)
					(width 0)
					(fill yes)
				)
			)
		)
	)
	(footprint ""
		(layer "F.Cu")
		(at 141.017498 -275.633942 90)
		(property "Reference" "R236"
			(at 0 0 90)
			(layer "F.SilkS")
			(hide yes)
			(effects
				(font
					(size 1.27 1.27)
				)
			)
		)
		(property "Value" "4K7R2J-2-GP"
			(at 0.064008 -3.993896 90)
			(unlocked yes)
			(layer "F.Fab")
			(hide yes)
			(effects
				(font
					(size 1.016 1.016)
					(thickness 0.1524)
				)
			)
		)
		(property "Device Type" "R402H16"
			(at 0.064008 -5.517896 90)
			(unlocked yes)
			(layer "F.Fab")
			(hide yes)
			(effects
				(font
					(size 1.016 1.016)
					(thickness 0.1524)
				)
			)
		)
		(duplicate_pad_numbers_are_jumpers no)
		(fp_line
			(start 0.508 -0.9398)
			(end -0.508 -0.9398)
			(stroke
				(width 0.1524)
				(type default)
			)
			(layer "F.SilkS")
		)
		(fp_line
			(start -0.508 -0.9398)
			(end -0.508 0.9398)
			(stroke
				(width 0.1524)
				(type default)
			)
			(layer "F.SilkS")
		)
		(fp_rect
			(start -0.508 0.9398)
			(end 0.508 -0.9398)
			(stroke
				(width 0)
				(type default)
			)
			(fill no)
			(layer "F.CrtYd")
		)
		(fp_rect
			(start -0.508 0.9398)
			(end 0.508 -0.9398)
			(stroke
				(width 0)
				(type default)
			)
			(fill no)
			(layer "F.Fab")
		)
		(pad "1" smd custom
			(at 0 -0.4445 90)
			(size 0.1397 0.1397)
			(layers "F.Cu" "F.Mask" "F.Paste")
			(net "P12V_A")
			(options
				(clearance outline)
				(anchor circle)
			)
			(primitives
				(gr_poly
					(pts
						(arc
							(start -0.1778 -0.2794)
							(mid -0.249642 -0.249642)
							(end -0.2794 -0.1778)
						)
						(arc
							(start -0.2794 0.1778)
							(mid -0.249642 0.249642)
							(end -0.1778 0.2794)
						)
						(arc
							(start 0.1778 0.2794)
							(mid 0.249642 0.249642)
							(end 0.2794 0.1778)
						)
						(arc
							(start 0.2794 -0.1778)
							(mid 0.249642 -0.249642)
							(end 0.1778 -0.2794)
						)
					)
					(width 0)
					(fill yes)
				)
			)
		)
		(pad "2" smd custom
			(at 0 0.4445 90)
			(size 0.1397 0.1397)
			(layers "F.Cu" "F.Mask" "F.Paste")
			(net "SW_HDD_R4")
			(options
				(clearance outline)
				(anchor circle)
			)
			(primitives
				(gr_poly
					(pts
						(arc
							(start -0.1778 -0.2794)
							(mid -0.249642 -0.249642)
							(end -0.2794 -0.1778)
						)
						(arc
							(start -0.2794 0.1778)
							(mid -0.249642 0.249642)
							(end -0.1778 0.2794)
						)
						(arc
							(start 0.1778 0.2794)
							(mid 0.249642 0.249642)
							(end 0.2794 0.1778)
						)
						(arc
							(start 0.2794 -0.1778)
							(mid 0.249642 -0.249642)
							(end 0.1778 -0.2794)
						)
					)
					(width 0)
					(fill yes)
				)
			)
		)
	)
	(footprint ""
		(layer "F.Cu")
		(at 145.106898 -294.683942 90)
		(property "Reference" "R225"
			(at 0 0 90)
			(layer "F.SilkS")
			(hide yes)
			(effects
				(font
					(size 1.27 1.27)
				)
			)
		)
		(property "Value" "2R6F-GP"
			(at -0.0508 -4.8514 90)
			(unlocked yes)
			(layer "F.Fab")
			(hide yes)
			(effects
				(font
					(size 1.016 1.016)
					(thickness 0.1524)
				)
			)
		)
		(property "Device Type" "R1206H26"
			(at 0 -6.3754 90)
			(unlocked yes)
			(layer "F.Fab")
			(hide yes)
			(effects
				(font
					(size 1.016 1.016)
					(thickness 0.1524)
				)
			)
		)
		(duplicate_pad_numbers_are_jumpers no)
		(fp_line
			(start 1.016 -2.2352)
			(end 1.016 2.2352)
			(stroke
				(width 0.1524)
				(type default)
			)
			(layer "F.SilkS")
		)
		(fp_line
			(start -1.016 -2.2352)
			(end 1.016 -2.2352)
			(stroke
				(width 0.1524)
				(type default)
			)
			(layer "F.SilkS")
		)
		(fp_line
			(start 1.016 2.2352)
			(end -1.016 2.2352)
			(stroke
				(width 0.1524)
				(type default)
			)
			(layer "F.SilkS")
		)
		(fp_line
			(start -1.016 2.2352)
			(end -1.016 -2.2352)
			(stroke
				(width 0.1524)
				(type default)
			)
			(layer "F.SilkS")
		)
		(fp_rect
			(start -1.0922 2.3114)
			(end 1.0922 -2.3114)
			(stroke
				(width 0)
				(type default)
			)
			(fill no)
			(layer "F.CrtYd")
		)
		(fp_poly
			(pts
				(xy -1.0922 -2.3114) (xy 1.0922 -2.3114) (xy 1.0922 2.3114) (xy -1.0922 2.3114)
			)
			(stroke
				(width 0)
				(type default)
			)
			(fill no)
			(layer "F.Fab")
		)
		(pad "1" smd rect
			(at 0 -1.397 90)
			(size 1.651 1.27)
			(layers "F.Cu" "F.Mask" "F.Paste")
			(net "P12V_HDD4")
		)
		(pad "2" smd rect
			(at 0 1.397 90)
			(size 1.651 1.27)
			(layers "F.Cu" "F.Mask" "F.Paste")
			(net "12V_PRE_4")
		)
	)
	(footprint ""
		(layer "F.Cu")
		(at 113.556796 -179.683918 90)
		(property "Reference" "R476"
			(at 0 0 90)
			(layer "F.SilkS")
			(hide yes)
			(effects
				(font
					(size 1.27 1.27)
				)
			)
		)
		(property "Value" "2R6F-GP"
			(at -0.0508 -4.8514 90)
			(unlocked yes)
			(layer "F.Fab")
			(hide yes)
			(effects
				(font
					(size 1.016 1.016)
					(thickness 0.1524)
				)
			)
		)
		(property "Device Type" "R1206H26"
			(at 0 -6.3754 90)
			(unlocked yes)
			(layer "F.Fab")
			(hide yes)
			(effects
				(font
					(size 1.016 1.016)
					(thickness 0.1524)
				)
			)
		)
		(duplicate_pad_numbers_are_jumpers no)
		(fp_line
			(start 1.016 -2.2352)
			(end 1.016 2.2352)
			(stroke
				(width 0.1524)
				(type default)
			)
			(layer "F.SilkS")
		)
		(fp_line
			(start -1.016 -2.2352)
			(end 1.016 -2.2352)
			(stroke
				(width 0.1524)
				(type default)
			)
			(layer "F.SilkS")
		)
		(fp_line
			(start 1.016 2.2352)
			(end -1.016 2.2352)
			(stroke
				(width 0.1524)
				(type default)
			)
			(layer "F.SilkS")
		)
		(fp_line
			(start -1.016 2.2352)
			(end -1.016 -2.2352)
			(stroke
				(width 0.1524)
				(type default)
			)
			(layer "F.SilkS")
		)
		(fp_rect
			(start -1.0922 2.3114)
			(end 1.0922 -2.3114)
			(stroke
				(width 0)
				(type default)
			)
			(fill no)
			(layer "F.CrtYd")
		)
		(fp_poly
			(pts
				(xy -1.0922 -2.3114) (xy 1.0922 -2.3114) (xy 1.0922 2.3114) (xy -1.0922 2.3114)
			)
			(stroke
				(width 0)
				(type default)
			)
			(fill no)
			(layer "F.Fab")
		)
		(pad "1" smd rect
			(at 0 -1.397 90)
			(size 1.651 1.27)
			(layers "F.Cu" "F.Mask" "F.Paste")
			(net "P12V_HDD15")
		)
		(pad "2" smd rect
			(at 0 1.397 90)
			(size 1.651 1.27)
			(layers "F.Cu" "F.Mask" "F.Paste")
			(net "12V_PRE_15")
		)
	)
	(footprint ""
		(layer "F.Cu")
		(at 117.646196 -161.014918 -90)
		(property "Reference" "R483"
			(at 0 0 270)
			(layer "F.SilkS")
			(hide yes)
			(effects
				(font
					(size 1.27 1.27)
				)
			)
		)
		(property "Value" "1KR2F-3-GP"
			(at 0.064008 -3.993896 270)
			(unlocked yes)
			(layer "F.Fab")
			(hide yes)
			(effects
				(font
					(size 1.016 1.016)
					(thickness 0.1524)
				)
			)
		)
		(property "Device Type" "R402H16"
			(at 0.064008 -5.517896 270)
			(unlocked yes)
			(layer "F.Fab")
			(hide yes)
			(effects
				(font
					(size 1.016 1.016)
					(thickness 0.1524)
				)
			)
		)
		(duplicate_pad_numbers_are_jumpers no)
		(fp_line
			(start -0.508 -0.9398)
			(end -0.508 0.9398)
			(stroke
				(width 0.1524)
				(type default)
			)
			(layer "F.SilkS")
		)
		(fp_line
			(start 0.508 -0.9398)
			(end -0.508 -0.9398)
			(stroke
				(width 0.1524)
				(type default)
			)
			(layer "F.SilkS")
		)
		(fp_rect
			(start -0.508 0.9398)
			(end 0.508 -0.9398)
			(stroke
				(width 0)
				(type default)
			)
			(fill no)
			(layer "F.CrtYd")
		)
		(fp_rect
			(start -0.508 0.9398)
			(end 0.508 -0.9398)
			(stroke
				(width 0)
				(type default)
			)
			(fill no)
			(layer "F.Fab")
		)
		(pad "1" smd custom
			(at 0 -0.4445 270)
			(size 0.1397 0.1397)
			(layers "F.Cu" "F.Mask" "F.Paste")
			(net "P3V3_STBY_A")
			(options
				(clearance outline)
				(anchor circle)
			)
			(primitives
				(gr_poly
					(pts
						(arc
							(start -0.1778 -0.2794)
							(mid -0.249642 -0.249642)
							(end -0.2794 -0.1778)
						)
						(arc
							(start -0.2794 0.1778)
							(mid -0.249642 0.249642)
							(end -0.1778 0.2794)
						)
						(arc
							(start 0.1778 0.2794)
							(mid 0.249642 0.249642)
							(end 0.2794 0.1778)
						)
						(arc
							(start 0.2794 -0.1778)
							(mid 0.249642 -0.249642)
							(end 0.1778 -0.2794)
						)
					)
					(width 0)
					(fill yes)
				)
			)
		)
		(pad "2" smd custom
			(at 0 0.4445 270)
			(size 0.1397 0.1397)
			(layers "F.Cu" "F.Mask" "F.Paste")
			(net "SW_PWR_R_HDD15")
			(options
				(clearance outline)
				(anchor circle)
			)
			(primitives
				(gr_poly
					(pts
						(arc
							(start -0.1778 -0.2794)
							(mid -0.249642 -0.249642)
							(end -0.2794 -0.1778)
						)
						(arc
							(start -0.2794 0.1778)
							(mid -0.249642 0.249642)
							(end -0.1778 0.2794)
						)
						(arc
							(start 0.1778 0.2794)
							(mid 0.249642 0.249642)
							(end 0.2794 0.1778)
						)
						(arc
							(start 0.2794 -0.1778)
							(mid 0.249642 -0.249642)
							(end 0.1778 -0.2794)
						)
					)
					(width 0)
					(fill yes)
				)
			)
		)
	)
	(footprint ""
		(layer "F.Cu")
		(at 244.856 -249.174 180)
		(property "Reference" "R46"
			(at 0 0 180)
			(layer "F.SilkS")
			(hide yes)
			(effects
				(font
					(size 1.27 1.27)
				)
			)
		)
		(property "Value" "4K7R2F-GP"
			(at 0.064008 -3.993896 180)
			(unlocked yes)
			(layer "F.Fab")
			(hide yes)
			(effects
				(font
					(size 1.016 1.016)
					(thickness 0.1524)
				)
			)
		)
		(property "Device Type" "R402H16"
			(at 0.064008 -5.517896 180)
			(unlocked yes)
			(layer "F.Fab")
			(hide yes)
			(effects
				(font
					(size 1.016 1.016)
					(thickness 0.1524)
				)
			)
		)
		(duplicate_pad_numbers_are_jumpers no)
		(fp_line
			(start 0.508 -0.9398)
			(end -0.508 -0.9398)
			(stroke
				(width 0.1524)
				(type default)
			)
			(layer "F.SilkS")
		)
		(fp_line
			(start -0.508 -0.9398)
			(end -0.508 0.9398)
			(stroke
				(width 0.1524)
				(type default)
			)
			(layer "F.SilkS")
		)
		(fp_rect
			(start -0.508 0.9398)
			(end 0.508 -0.9398)
			(stroke
				(width 0)
				(type default)
			)
			(fill no)
			(layer "F.CrtYd")
		)
		(fp_rect
			(start -0.508 0.9398)
			(end 0.508 -0.9398)
			(stroke
				(width 0)
				(type default)
			)
			(fill no)
			(layer "F.Fab")
		)
		(pad "1" smd custom
			(at 0 -0.4445 180)
			(size 0.1397 0.1397)
			(layers "F.Cu" "F.Mask" "F.Paste")
			(net "P3V3_STBY_A")
			(options
				(clearance outline)
				(anchor circle)
			)
			(primitives
				(gr_poly
					(pts
						(arc
							(start -0.1778 -0.2794)
							(mid -0.249642 -0.249642)
							(end -0.2794 -0.1778)
						)
						(arc
							(start -0.2794 0.1778)
							(mid -0.249642 0.249642)
							(end -0.1778 0.2794)
						)
						(arc
							(start 0.1778 0.2794)
							(mid 0.249642 0.249642)
							(end 0.2794 0.1778)
						)
						(arc
							(start 0.2794 -0.1778)
							(mid 0.249642 -0.249642)
							(end 0.1778 -0.2794)
						)
					)
					(width 0)
					(fill yes)
				)
			)
		)
		(pad "2" smd custom
			(at 0 0.4445 180)
			(size 0.1397 0.1397)
			(layers "F.Cu" "F.Mask" "F.Paste")
			(net "IO_EXP5_A2")
			(options
				(clearance outline)
				(anchor circle)
			)
			(primitives
				(gr_poly
					(pts
						(arc
							(start -0.1778 -0.2794)
							(mid -0.249642 -0.249642)
							(end -0.2794 -0.1778)
						)
						(arc
							(start -0.2794 0.1778)
							(mid -0.249642 0.249642)
							(end -0.1778 0.2794)
						)
						(arc
							(start 0.1778 0.2794)
							(mid 0.249642 0.249642)
							(end 0.2794 0.1778)
						)
						(arc
							(start 0.2794 -0.1778)
							(mid 0.249642 -0.249642)
							(end 0.1778 -0.2794)
						)
					)
					(width 0)
					(fill yes)
				)
			)
		)
	)
	(footprint ""
		(layer "F.Cu")
		(at 64.013334 -274.219416 90)
		(property "Reference" "C51"
			(at 0 0 90)
			(layer "F.SilkS")
			(hide yes)
			(effects
				(font
					(size 1.27 1.27)
				)
			)
		)
		(property "Value" "SCD01U16V1KX-GP"
			(at -2.8321 -1.7399 90)
			(unlocked yes)
			(layer "F.Fab")
			(hide yes)
			(effects
				(font
					(size 1.016 1.016)
					(thickness 0.1524)
				)
			)
		)
		(property "Device Type" "C0201H13"
			(at -2.8321 -3.2639 90)
			(unlocked yes)
			(layer "F.Fab")
			(hide yes)
			(effects
				(font
					(size 1.016 1.016)
					(thickness 0.1524)
				)
			)
		)
		(duplicate_pad_numbers_are_jumpers no)
		(fp_rect
			(start -0.2794 0.6477)
			(end 0.2794 -0.6477)
			(stroke
				(width 0)
				(type default)
			)
			(fill no)
			(layer "F.CrtYd")
		)
		(fp_rect
			(start -0.2794 0.6477)
			(end 0.2794 -0.6477)
			(stroke
				(width 0)
				(type default)
			)
			(fill no)
			(layer "F.Fab")
		)
		(pad "1" smd custom
			(at 0 -0.2794 90)
			(size 0.0762 0.0762)
			(layers "F.Cu" "F.Mask" "F.Paste")
			(net "SAS_HDD_RX_N1")
			(options
				(clearance outline)
				(anchor circle)
			)
			(primitives
				(gr_poly
					(pts
						(arc
							(start 0.1524 -0.127)
							(mid 0.137521 -0.162921)
							(end 0.1016 -0.1778)
						)
						(arc
							(start -0.1016 -0.1778)
							(mid -0.137521 -0.162921)
							(end -0.1524 -0.127)
						)
						(arc
							(start -0.1524 0.127)
							(mid -0.137521 0.162921)
							(end -0.1016 0.1778)
						)
						(arc
							(start 0.1016 0.1778)
							(mid 0.137521 0.162921)
							(end 0.1524 0.127)
						)
					)
					(width 0)
					(fill yes)
				)
			)
		)
		(pad "2" smd custom
			(at 0 0.2794 90)
			(size 0.0762 0.0762)
			(layers "F.Cu" "F.Mask" "F.Paste")
			(net "PHY_SCC_A_TO_DRV_A_1_DN")
			(options
				(clearance outline)
				(anchor circle)
			)
			(primitives
				(gr_poly
					(pts
						(arc
							(start 0.1524 -0.127)
							(mid 0.137521 -0.162921)
							(end 0.1016 -0.1778)
						)
						(arc
							(start -0.1016 -0.1778)
							(mid -0.137521 -0.162921)
							(end -0.1524 -0.127)
						)
						(arc
							(start -0.1524 0.127)
							(mid -0.137521 0.162921)
							(end -0.1016 0.1778)
						)
						(arc
							(start 0.1016 0.1778)
							(mid 0.137521 0.162921)
							(end 0.1524 0.127)
						)
					)
					(width 0)
					(fill yes)
				)
			)
		)
	)
)
